(kicad_pcb
	(version 20260206)
	(generator "pcbnew")
	(generator_version "10.0")
	(general
		(thickness 1.6)
		(legacy_teardrops no)
	)
	(paper "A4")
	(title_block
		(title "12092022_DA0F0TFB6D0_F0T_FAN_BOARD_MP5048_D_brd_v02_OCP.brd")
		(comment 1 "Grand Teton / footprints 77-79 of 924")
	)
	(layers
		(0 "F.Cu" signal "TOP")
		(4 "In1.Cu" signal "GND")
		(6 "In2.Cu" signal "IN1")
		(8 "In3.Cu" signal "IN2")
		(10 "In4.Cu" signal "GND1")
		(2 "B.Cu" signal "BOTTOM")
		(9 "F.Adhes" user "F.Adhesive")
		(11 "B.Adhes" user "B.Adhesive")
		(13 "F.Paste" user "Package Geometry/Pastemask Top")
		(15 "B.Paste" user "Package Geometry/Pastemask Bottom")
		(5 "F.SilkS" user "Ref Des/Silkscreen Top")
		(7 "B.SilkS" user "Ref Des/Silkscreen Bottom")
		(1 "F.Mask" user "Board Geometry/Soldermask Top")
		(3 "B.Mask" user "Board Geometry/Soldermask Bottom")
		(17 "Dwgs.User" user "User.Drawings")
		(19 "Cmts.User" user "User.Comments")
		(21 "Eco1.User" user "User.Eco1")
		(23 "Eco2.User" user "User.Eco2")
		(25 "Edge.Cuts" user "Board Geometry/Outline")
		(27 "Margin" user)
		(31 "F.CrtYd" user "Package Geometry/Place Bound Top")
		(29 "B.CrtYd" user "Package Geometry/Place Bound Bottom")
		(35 "F.Fab" user "Ref Des/Assembly Top")
		(33 "B.Fab" user "Ref Des/Assembly Bottom")
	)
	(footprint ""
		(layer "F.Cu")
		(at 31.496 -129.159 90)
		(property "Reference" "U317"
			(at -2.032 4.34467 90)
			(unlocked yes)
			(layer "F.SilkS")
			(effects
				(font
					(size 0.7874 0.5842)
					(thickness 0.1524)
				)
				(justify left)
			)
		)
		(property "Value" ""
			(at 0 0 90)
			(layer "F.Fab")
			(effects
				(font
					(size 1.27 1.27)
				)
			)
		)
		(duplicate_pad_numbers_are_jumpers no)
		(fp_line
			(start 0 -3.048)
			(end 0 -2.54)
			(stroke
				(width 0.1524)
				(type default)
			)
			(layer "F.SilkS")
		)
		(fp_line
			(start 2.050034 -2.050034)
			(end 1.41859 -2.050034)
			(stroke
				(width 0.1524)
				(type default)
			)
			(layer "F.SilkS")
		)
		(fp_line
			(start -1.42367 -2.050034)
			(end -2.050034 -2.050034)
			(stroke
				(width 0.1524)
				(type default)
			)
			(layer "F.SilkS")
		)
		(fp_line
			(start -2.050034 -2.050034)
			(end -2.050034 -1.4224)
			(stroke
				(width 0.1524)
				(type default)
			)
			(layer "F.SilkS")
		)
		(fp_line
			(start 2.050034 -1.415796)
			(end 2.050034 -2.050034)
			(stroke
				(width 0.1524)
				(type default)
			)
			(layer "F.SilkS")
		)
		(fp_line
			(start 3.302 -0.8128)
			(end 2.54 -0.8128)
			(stroke
				(width 0.1524)
				(type default)
			)
			(layer "F.SilkS")
		)
		(fp_line
			(start -2.54508 0.398272)
			(end -3.05308 0.398272)
			(stroke
				(width 0.1524)
				(type default)
			)
			(layer "F.SilkS")
		)
		(fp_line
			(start 3.048 1.2192)
			(end 2.54 1.2192)
			(stroke
				(width 0.1524)
				(type default)
			)
			(layer "F.SilkS")
		)
		(fp_line
			(start -2.050034 1.41986)
			(end -2.050034 2.050034)
			(stroke
				(width 0.1524)
				(type default)
			)
			(layer "F.SilkS")
		)
		(fp_line
			(start 2.050034 2.050034)
			(end 2.050034 1.41732)
			(stroke
				(width 0.1524)
				(type default)
			)
			(layer "F.SilkS")
		)
		(fp_line
			(start 1.42367 2.050034)
			(end 2.050034 2.050034)
			(stroke
				(width 0.1524)
				(type default)
			)
			(layer "F.SilkS")
		)
		(fp_line
			(start -2.050034 2.050034)
			(end -1.417828 2.050034)
			(stroke
				(width 0.1524)
				(type default)
			)
			(layer "F.SilkS")
		)
		(fp_line
			(start -0.4064 2.54)
			(end -0.4064 3.302)
			(stroke
				(width 0.1524)
				(type default)
			)
			(layer "F.SilkS")
		)
		(fp_poly
			(pts
				(xy -3.6957 -1.890776) (xy -3.6957 -0.874776) (xy -2.6797 -1.382776)
			)
			(stroke
				(width 0)
				(type default)
			)
			(fill yes)
			(layer "F.SilkS")
		)
		(fp_line
			(start 0.009652 -3.052572)
			(end 0.009652 -2.544572)
			(stroke
				(width 0.1)
				(type default)
			)
			(layer "F.Fab")
		)
		(fp_line
			(start 2.050034 -2.050034)
			(end -2.050034 -2.050034)
			(stroke
				(width 0.1)
				(type default)
			)
			(layer "F.Fab")
		)
		(fp_line
			(start -2.050034 -2.050034)
			(end -2.050034 2.050034)
			(stroke
				(width 0.1)
				(type default)
			)
			(layer "F.Fab")
		)
		(fp_line
			(start 3.319272 -0.80264)
			(end 2.557272 -0.80264)
			(stroke
				(width 0.1)
				(type default)
			)
			(layer "F.Fab")
		)
		(fp_line
			(start -2.54508 0.398272)
			(end -3.05308 0.398272)
			(stroke
				(width 0.1)
				(type default)
			)
			(layer "F.Fab")
		)
		(fp_line
			(start 3.062732 1.198372)
			(end 2.554732 1.198372)
			(stroke
				(width 0.1)
				(type default)
			)
			(layer "F.Fab")
		)
		(fp_line
			(start 2.050034 2.050034)
			(end 2.050034 -2.050034)
			(stroke
				(width 0.1)
				(type default)
			)
			(layer "F.Fab")
		)
		(fp_line
			(start -2.050034 2.050034)
			(end 2.050034 2.050034)
			(stroke
				(width 0.1)
				(type default)
			)
			(layer "F.Fab")
		)
		(fp_line
			(start -0.396748 2.568448)
			(end -0.396748 3.330448)
			(stroke
				(width 0.1)
				(type default)
			)
			(layer "F.Fab")
		)
		(fp_poly
			(pts
				(xy -3.5052 -1.707896) (xy -3.5052 -0.691896) (xy -2.4892 -1.199896)
			)
			(stroke
				(width 0)
				(type default)
			)
			(fill yes)
			(layer "F.Fab")
		)
		(fp_text user "22"
			(at 1.41605 -2.684018 90)
			(unlocked yes)
			(layer "F.SilkS")
			(effects
				(font
					(size 0.635 0.4064)
					(thickness 0.1524)
				)
				(justify left)
			)
		)
		(fp_text user "28"
			(at -2.38125 -2.576068 90)
			(unlocked yes)
			(layer "F.SilkS")
			(effects
				(font
					(size 0.635 0.4064)
					(thickness 0.1524)
				)
				(justify left)
			)
		)
		(fp_text user "21"
			(at 2.618232 -1.3843 180)
			(unlocked yes)
			(layer "F.SilkS")
			(effects
				(font
					(size 0.635 0.4064)
					(thickness 0.1524)
				)
				(justify left)
			)
		)
		(fp_text user "7"
			(at -2.69875 2.286 180)
			(unlocked yes)
			(layer "F.SilkS")
			(effects
				(font
					(size 0.635 0.4064)
					(thickness 0.1524)
				)
				(justify left)
			)
		)
		(fp_text user "15"
			(at 2.630932 2.33045 180)
			(unlocked yes)
			(layer "F.SilkS")
			(effects
				(font
					(size 0.635 0.4064)
					(thickness 0.1524)
				)
				(justify left)
			)
		)
		(fp_text user "8"
			(at -1.92405 2.586482 90)
			(unlocked yes)
			(layer "F.SilkS")
			(effects
				(font
					(size 0.635 0.4064)
					(thickness 0.1524)
				)
				(justify left)
			)
		)
		(fp_text user "14"
			(at 1.3208 2.745232 90)
			(unlocked yes)
			(layer "F.SilkS")
			(effects
				(font
					(size 0.635 0.4064)
					(thickness 0.1524)
				)
				(justify left)
			)
		)
		(fp_text user "22"
			(at 1.41605 -2.684018 90)
			(unlocked yes)
			(layer "F.Fab")
			(effects
				(font
					(size 0.635 0.4064)
					(thickness 0.1524)
				)
				(justify left)
			)
		)
		(fp_text user "28"
			(at -2.38125 -2.576068 90)
			(unlocked yes)
			(layer "F.Fab")
			(effects
				(font
					(size 0.635 0.4064)
					(thickness 0.1524)
				)
				(justify left)
			)
		)
		(fp_text user "21"
			(at 2.618232 -1.3843 180)
			(unlocked yes)
			(layer "F.Fab")
			(effects
				(font
					(size 0.635 0.4064)
					(thickness 0.1524)
				)
				(justify left)
			)
		)
		(fp_text user "7"
			(at -2.563368 1.8923 180)
			(unlocked yes)
			(layer "F.Fab")
			(effects
				(font
					(size 0.635 0.4064)
					(thickness 0.1524)
				)
				(justify left)
			)
		)
		(fp_text user "15"
			(at 2.630932 2.33045 180)
			(unlocked yes)
			(layer "F.Fab")
			(effects
				(font
					(size 0.635 0.4064)
					(thickness 0.1524)
				)
				(justify left)
			)
		)
		(fp_text user "8"
			(at -1.92405 2.586482 90)
			(unlocked yes)
			(layer "F.Fab")
			(effects
				(font
					(size 0.635 0.4064)
					(thickness 0.1524)
				)
				(justify left)
			)
		)
		(fp_text user "14"
			(at 1.3208 2.745232 90)
			(unlocked yes)
			(layer "F.Fab")
			(effects
				(font
					(size 0.635 0.4064)
					(thickness 0.1524)
				)
				(justify left)
			)
		)
		(pad "1" smd rect
			(at -1.999996 -1.199896 180)
			(size 0.1778 0.8128)
			(layers "F.Cu" "F.Mask" "F.Paste")
			(net "MAX31790_U317_FREQ_START")
		)
		(pad "2" smd rect
			(at -1.999996 -0.8001 180)
			(size 0.1778 0.8128)
			(layers "F.Cu" "F.Mask" "F.Paste")
			(net "MAX31790_U317_SPIN_START")
		)
		(pad "3" smd rect
			(at -1.999996 -0.40005 180)
			(size 0.1778 0.8128)
			(layers "F.Cu" "F.Mask" "F.Paste")
			(net "MAX31790_U317_ADD1")
		)
		(pad "4" smd rect
			(at -1.999996 0 180)
			(size 0.1778 0.8128)
			(layers "F.Cu" "F.Mask" "F.Paste")
			(net "MAX31790_U317_ADD0")
		)
		(pad "5" smd rect
			(at -1.999996 0.40005 180)
			(size 0.1778 0.8128)
			(layers "F.Cu" "F.Mask" "F.Paste")
			(net "MAX31790_U317_WD_START")
		)
		(pad "6" smd rect
			(at -1.999996 0.8001 180)
			(size 0.1778 0.8128)
			(layers "F.Cu" "F.Mask" "F.Paste")
			(net "TP_U317_XTAL2")
		)
		(pad "7" smd rect
			(at -1.999996 1.199896 180)
			(size 0.1778 0.8128)
			(layers "F.Cu" "F.Mask" "F.Paste")
			(net "TP_U317_XTAL1")
		)
		(pad "8" smd rect
			(at -1.199896 1.999996 90)
			(size 0.1778 0.8128)
			(layers "F.Cu" "F.Mask" "F.Paste")
			(net "GND")
		)
		(pad "9" smd rect
			(at -0.8001 1.999996 90)
			(size 0.1778 0.8128)
			(layers "F.Cu" "F.Mask" "F.Paste")
			(net "FAN_3_TACH_OL_R1")
		)
		(pad "10" smd rect
			(at -0.40005 1.999996 90)
			(size 0.1778 0.8128)
			(layers "F.Cu" "F.Mask" "F.Paste")
			(net "FAN_3_PWM_R1")
		)
		(pad "11" smd rect
			(at 0 1.999996 90)
			(size 0.1778 0.8128)
			(layers "F.Cu" "F.Mask" "F.Paste")
			(net "FAN_2_TACH_OL_R1")
		)
		(pad "12" smd rect
			(at 0.40005 1.999996 90)
			(size 0.1778 0.8128)
			(layers "F.Cu" "F.Mask" "F.Paste")
			(net "FAN_3_TACH_IL_R1")
		)
		(pad "13" smd rect
			(at 0.8001 1.999996 90)
			(size 0.1778 0.8128)
			(layers "F.Cu" "F.Mask" "F.Paste")
			(net "FAN_2_TACH_IL_R1")
		)
		(pad "14" smd rect
			(at 1.199896 1.999996 90)
			(size 0.1778 0.8128)
			(layers "F.Cu" "F.Mask" "F.Paste")
			(net "FAN_2_PWM_R1")
		)
		(pad "15" smd rect
			(at 1.999996 1.199896 180)
			(size 0.1778 0.8128)
			(layers "F.Cu" "F.Mask" "F.Paste")
			(net "FAN_1_TACH_OL_R1")
		)
		(pad "16" smd rect
			(at 1.999996 0.8001 180)
			(size 0.1778 0.8128)
			(layers "F.Cu" "F.Mask" "F.Paste")
			(net "FAN_1_PWM_R1")
		)
		(pad "17" smd rect
			(at 1.999996 0.40005 180)
			(size 0.1778 0.8128)
			(layers "F.Cu" "F.Mask" "F.Paste")
			(net "FAN_0_TACH_OL_R1")
		)
		(pad "18" smd rect
			(at 1.999996 0 180)
			(size 0.1778 0.8128)
			(layers "F.Cu" "F.Mask" "F.Paste")
			(net "FAN_1_TACH_IL_R1")
		)
		(pad "19" smd rect
			(at 1.999996 -0.40005 180)
			(size 0.1778 0.8128)
			(layers "F.Cu" "F.Mask" "F.Paste")
			(net "FAN_0_TACH_IL_R1")
		)
		(pad "20" smd rect
			(at 1.999996 -0.8001 180)
			(size 0.1778 0.8128)
			(layers "F.Cu" "F.Mask" "F.Paste")
			(net "FAN_0_PWM_R1")
		)
		(pad "21" smd rect
			(at 1.999996 -1.199896 180)
			(size 0.1778 0.8128)
			(layers "F.Cu" "F.Mask" "F.Paste")
			(net "P3V3_AUX")
		)
		(pad "22" smd rect
			(at 1.199896 -1.999996 90)
			(size 0.1778 0.8128)
			(layers "F.Cu" "F.Mask" "F.Paste")
			(net "SMB_PDBV_FAN_R_U317_SDA")
		)
		(pad "23" smd rect
			(at 0.8001 -1.999996 90)
			(size 0.1778 0.8128)
			(layers "F.Cu" "F.Mask" "F.Paste")
			(net "SMB_PDBV_FAN_R_U317_SCL")
		)
		(pad "24" smd rect
			(at 0.40005 -1.999996 90)
			(size 0.1778 0.8128)
			(layers "F.Cu" "F.Mask" "F.Paste")
			(net "U317_FAN FAIL_N")
		)
		(pad "25" smd rect
			(at 0 -1.999996 90)
			(size 0.1778 0.8128)
			(layers "F.Cu" "F.Mask" "F.Paste")
			(net "MAX31790_U317_PWM_START0")
		)
		(pad "26" smd rect
			(at -0.40005 -1.999996 90)
			(size 0.1778 0.8128)
			(layers "F.Cu" "F.Mask" "F.Paste")
			(net "MAX31790_U317_PWM_START1")
		)
		(pad "27" smd rect
			(at -0.8001 -1.999996 90)
			(size 0.1778 0.8128)
			(layers "F.Cu" "F.Mask" "F.Paste")
			(net "U317_FAN FS_N")
		)
		(pad "28" smd rect
			(at -1.199896 -1.999996 90)
			(size 0.1778 0.8128)
			(layers "F.Cu" "F.Mask" "F.Paste")
			(net "NC_U317_CLKOUT")
		)
		(pad "TH" smd rect
			(at 0 0 180)
			(size 2.7178 2.7178)
			(layers "F.Cu" "F.Mask" "F.Paste")
			(net "GND")
		)
		(zone
			(layer "F.Cu")
			(hatch none 0.5)
			(connect_pads
				(clearance 0)
			)
			(min_thickness 0.25)
			(keepout
				(tracks not_allowed)
				(vias allowed)
				(pads allowed)
				(copperpour not_allowed)
				(footprints allowed)
			)
			(placement
				(enabled no)
				(sheetname "")
			)
			(fill
				(thermal_gap 0.5)
				(thermal_bridge_width 0.5)
				(island_removal_mode 0)
			)
			(polygon
				(pts
					(xy 29.9593 -128.9304) (xy 30.07995 -128.9304) (xy 30.07995 -127.74295) (xy 32.91205 -127.74295)
					(xy 32.91205 -130.57505) (xy 30.07995 -130.57505) (xy 30.07995 -128.9558) (xy 29.9593 -128.9558)
					(xy 29.9593 -130.6957) (xy 33.0327 -130.6957) (xy 33.0327 -127.6223) (xy 29.9593 -127.6223)
				)
			)
		)
	)
	(footprint ""
		(layer "F.Cu")
		(at 7.112 -64.897 180)
		(property "Reference" "PR49"
			(at 0 0 180)
			(layer "F.SilkS")
			(hide yes)
			(effects
				(font
					(size 1.27 1.27)
				)
			)
		)
		(property "Value" ""
			(at 0 0 180)
			(layer "F.Fab")
			(effects
				(font
					(size 1.27 1.27)
				)
			)
		)
		(duplicate_pad_numbers_are_jumpers no)
		(fp_line
			(start 0.7874 0.4064)
			(end -0.7874 0.4064)
			(stroke
				(width 0.1524)
				(type default)
			)
			(layer "F.SilkS")
		)
		(fp_line
			(start 0.7874 -0.4064)
			(end 0.7874 0.4064)
			(stroke
				(width 0.1524)
				(type default)
			)
			(layer "F.SilkS")
		)
		(fp_line
			(start -0.7874 0.4064)
			(end -0.7874 -0.4064)
			(stroke
				(width 0.1524)
				(type default)
			)
			(layer "F.SilkS")
		)
		(fp_line
			(start -0.7874 -0.4064)
			(end 0.7874 -0.4064)
			(stroke
				(width 0.1524)
				(type default)
			)
			(layer "F.SilkS")
		)
		(fp_line
			(start 0.67945 0.3048)
			(end 0.120396 0.3048)
			(stroke
				(width 0.1)
				(type default)
			)
			(layer "F.Fab")
		)
		(fp_line
			(start 0.67945 -0.3048)
			(end 0.67945 0.3048)
			(stroke
				(width 0.1)
				(type default)
			)
			(layer "F.Fab")
		)
		(fp_line
			(start 0.12065 -0.2794)
			(end 0.12065 -0.3048)
			(stroke
				(width 0.1)
				(type default)
			)
			(layer "F.Fab")
		)
		(fp_line
			(start 0.12065 -0.3048)
			(end 0.67945 -0.3048)
			(stroke
				(width 0.1)
				(type default)
			)
			(layer "F.Fab")
		)
		(fp_line
			(start 0.120396 0.3048)
			(end 0.120396 0.2794)
			(stroke
				(width 0.1)
				(type default)
			)
			(layer "F.Fab")
		)
		(fp_line
			(start 0.120396 0.2794)
			(end -0.12065 0.2794)
			(stroke
				(width 0.1)
				(type default)
			)
			(layer "F.Fab")
		)
		(fp_line
			(start -0.12065 0.3048)
			(end -0.67945 0.3048)
			(stroke
				(width 0.1)
				(type default)
			)
			(layer "F.Fab")
		)
		(fp_line
			(start -0.12065 0.2794)
			(end -0.12065 0.3048)
			(stroke
				(width 0.1)
				(type default)
			)
			(layer "F.Fab")
		)
		(fp_line
			(start -0.12065 -0.2794)
			(end 0.12065 -0.2794)
			(stroke
				(width 0.1)
				(type default)
			)
			(layer "F.Fab")
		)
		(fp_line
			(start -0.12065 -0.305054)
			(end -0.12065 -0.2794)
			(stroke
				(width 0.1)
				(type default)
			)
			(layer "F.Fab")
		)
		(fp_line
			(start -0.67945 0.3048)
			(end -0.67945 -0.305054)
			(stroke
				(width 0.1)
				(type default)
			)
			(layer "F.Fab")
		)
		(fp_line
			(start -0.67945 -0.305054)
			(end -0.12065 -0.305054)
			(stroke
				(width 0.1)
				(type default)
			)
			(layer "F.Fab")
		)
		(pad "1" smd circle
			(at -0.40005 0 180)
			(size 0 0)
			(layers "F.Cu" "F.Mask" "F.Paste")
			(net "FAN_4_P3V_R")
		)
		(pad "2" smd circle
			(at 0.40005 0 180)
			(size 0 0)
			(layers "F.Cu" "F.Mask" "F.Paste")
			(net "FAN_4_MODE")
		)
	)
	(footprint ""
		(layer "F.Cu")
		(at 38.6461 -128.778)
		(property "Reference" "R5580"
			(at 0 0 0)
			(layer "F.SilkS")
			(hide yes)
			(effects
				(font
					(size 1.27 1.27)
				)
			)
		)
		(property "Value" ""
			(at 0 0 0)
			(layer "F.Fab")
			(effects
				(font
					(size 1.27 1.27)
				)
			)
		)
		(duplicate_pad_numbers_are_jumpers no)
		(fp_line
			(start -0.7874 -0.4064)
			(end 0.7874 -0.4064)
			(stroke
				(width 0.1524)
				(type default)
			)
			(layer "F.SilkS")
		)
		(fp_line
			(start -0.7874 0.4064)
			(end -0.7874 -0.4064)
			(stroke
				(width 0.1524)
				(type default)
			)
			(layer "F.SilkS")
		)
		(fp_line
			(start 0.7874 -0.4064)
			(end 0.7874 0.4064)
			(stroke
				(width 0.1524)
				(type default)
			)
			(layer "F.SilkS")
		)
		(fp_line
			(start 0.7874 0.4064)
			(end -0.7874 0.4064)
			(stroke
				(width 0.1524)
				(type default)
			)
			(layer "F.SilkS")
		)
		(fp_line
			(start -0.67945 -0.305054)
			(end -0.12065 -0.305054)
			(stroke
				(width 0.1)
				(type default)
			)
			(layer "F.Fab")
		)
		(fp_line
			(start -0.67945 0.3048)
			(end -0.67945 -0.305054)
			(stroke
				(width 0.1)
				(type default)
			)
			(layer "F.Fab")
		)
		(fp_line
			(start -0.12065 -0.305054)
			(end -0.12065 -0.2794)
			(stroke
				(width 0.1)
				(type default)
			)
			(layer "F.Fab")
		)
		(fp_line
			(start -0.12065 -0.2794)
			(end 0.12065 -0.2794)
			(stroke
				(width 0.1)
				(type default)
			)
			(layer "F.Fab")
		)
		(fp_line
			(start -0.12065 0.2794)
			(end -0.12065 0.3048)
			(stroke
				(width 0.1)
				(type default)
			)
			(layer "F.Fab")
		)
		(fp_line
			(start -0.12065 0.3048)
			(end -0.67945 0.3048)
			(stroke
				(width 0.1)
				(type default)
			)
			(layer "F.Fab")
		)
		(fp_line
			(start 0.120396 0.2794)
			(end -0.12065 0.2794)
			(stroke
				(width 0.1)
				(type default)
			)
			(layer "F.Fab")
		)
		(fp_line
			(start 0.120396 0.3048)
			(end 0.120396 0.2794)
			(stroke
				(width 0.1)
				(type default)
			)
			(layer "F.Fab")
		)
		(fp_line
			(start 0.12065 -0.3048)
			(end 0.67945 -0.3048)
			(stroke
				(width 0.1)
				(type default)
			)
			(layer "F.Fab")
		)
		(fp_line
			(start 0.12065 -0.2794)
			(end 0.12065 -0.3048)
			(stroke
				(width 0.1)
				(type default)
			)
			(layer "F.Fab")
		)
		(fp_line
			(start 0.67945 -0.3048)
			(end 0.67945 0.3048)
			(stroke
				(width 0.1)
				(type default)
			)
			(layer "F.Fab")
		)
		(fp_line
			(start 0.67945 0.3048)
			(end 0.120396 0.3048)
			(stroke
				(width 0.1)
				(type default)
			)
			(layer "F.Fab")
		)
		(pad "1" smd rect
			(at -0.40005 0 180)
			(size 0.4572 0.508)
			(layers "F.Cu" "F.Mask" "F.Paste")
			(net "FAN_2_TACH_IL")
		)
		(pad "2" smd rect
			(at 0.40005 0 180)
			(size 0.4572 0.508)
			(layers "F.Cu" "F.Mask" "F.Paste")
			(net "FAN_2_TACH_IL_R2")
		)
	)
)
